# S9S_MB_2U (Grand Teton) — schematic netlist excerpt (pin names and nets, part order shuffled) for the footprints in the layout excerpt that follows; sources: Cadence DE-HDL packaged netlist, KiCad conversion of 03242023_DA0F0TMBIJ0_F0T_Motherboard_J_brd_V01_OCP.brd

C1011  Q_CAP  22UF 4V 20% X6S  pkg C0402  page 74 : A = PVCCIN_CPU0 ; B = GND
R996  Q_RES  33.2 1% CHIP  pkg 0402LF  page 236 : A = SMB_S3M_CPU1_SDA ; B = SMB_S3M_CPU1_R_SDA

(kicad_pcb
	(version 20260206)
	(generator "pcbnew")
	(generator_version "10.0")
	(general
		(thickness 1.6)
		(legacy_teardrops no)
	)
	(paper "A4")
	(title_block
		(title "03242023_DA0F0TMBIJ0_F0T_Motherboard_J_brd_V01_OCP.brd")
		(comment 1 "Grand Teton / footprints 4058-4059 of 6105")
	)
	(layers
		(0 "F.Cu" signal "TOP")
		(4 "In1.Cu" signal "GND")
		(6 "In2.Cu" signal "IN1")
		(8 "In3.Cu" signal "GND1")
		(10 "In4.Cu" signal "IN2")
		(12 "In5.Cu" signal "GND2")
		(14 "In6.Cu" signal "IN3")
		(16 "In7.Cu" signal "GND3")
		(18 "In8.Cu" signal "VCC")
		(20 "In9.Cu" signal "VCC1")
		(22 "In10.Cu" signal "GND4")
		(24 "In11.Cu" signal "IN4")
		(26 "In12.Cu" signal "GND5")
		(28 "In13.Cu" signal "IN5")
		(30 "In14.Cu" signal "GND6")
		(32 "In15.Cu" signal "IN6")
		(34 "In16.Cu" signal "GND7")
		(2 "B.Cu" signal "BOTTOM")
		(9 "F.Adhes" user "F.Adhesive")
		(11 "B.Adhes" user "B.Adhesive")
		(13 "F.Paste" user "Package Geometry/Pastemask Top")
		(15 "B.Paste" user "Package Geometry/Pastemask Bottom")
		(5 "F.SilkS" user "Ref Des/Silkscreen Top")
		(7 "B.SilkS" user "Ref Des/Silkscreen Bottom")
		(1 "F.Mask" user "Board Geometry/Soldermask Top")
		(3 "B.Mask" user "Board Geometry/Soldermask Bottom")
		(17 "Dwgs.User" user "User.Drawings")
		(19 "Cmts.User" user "User.Comments")
		(21 "Eco1.User" user "User.Eco1")
		(23 "Eco2.User" user "User.Eco2")
		(25 "Edge.Cuts" user "Board Geometry/Outline")
		(27 "Margin" user)
		(31 "F.CrtYd" user "Package Geometry/Place Bound Top")
		(29 "B.CrtYd" user "Package Geometry/Place Bound Bottom")
		(35 "F.Fab" user "Ref Des/Assembly Top")
		(33 "B.Fab" user "Ref Des/Assembly Bottom")
	)
	(footprint ""
		(layer "F.Cu")
		(at 352.281744 -241.976656 -90)
		(property "Reference" "C1011"
			(at 0 0 270)
			(layer "F.SilkS")
			(hide yes)
			(effects
				(font
					(size 1.27 1.27)
				)
			)
		)
		(property "Value" ""
			(at 0 0 270)
			(layer "F.Fab")
			(effects
				(font
					(size 1.27 1.27)
				)
			)
		)
		(duplicate_pad_numbers_are_jumpers no)
		(fp_line
			(start -0.7874 0.4064)
			(end -0.7874 -0.4064)
			(stroke
				(width 0.1524)
				(type default)
			)
			(layer "F.SilkS")
		)
		(fp_line
			(start 0.7874 0.4064)
			(end -0.7874 0.4064)
			(stroke
				(width 0.1524)
				(type default)
			)
			(layer "F.SilkS")
		)
		(fp_line
			(start -0.7874 -0.4064)
			(end 0.7874 -0.4064)
			(stroke
				(width 0.1524)
				(type default)
			)
			(layer "F.SilkS")
		)
		(fp_line
			(start 0.7874 -0.4064)
			(end 0.7874 0.4064)
			(stroke
				(width 0.1524)
				(type default)
			)
			(layer "F.SilkS")
		)
		(fp_line
			(start -0.67945 0.3048)
			(end -0.67945 -0.305054)
			(stroke
				(width 0.1)
				(type default)
			)
			(layer "F.Fab")
		)
		(fp_line
			(start -0.12065 0.3048)
			(end -0.67945 0.3048)
			(stroke
				(width 0.1)
				(type default)
			)
			(layer "F.Fab")
		)
		(fp_line
			(start 0.120396 0.3048)
			(end 0.120396 0.2794)
			(stroke
				(width 0.1)
				(type default)
			)
			(layer "F.Fab")
		)
		(fp_line
			(start 0.67945 0.3048)
			(end 0.120396 0.3048)
			(stroke
				(width 0.1)
				(type default)
			)
			(layer "F.Fab")
		)
		(fp_line
			(start -0.12065 0.2794)
			(end -0.12065 0.3048)
			(stroke
				(width 0.1)
				(type default)
			)
			(layer "F.Fab")
		)
		(fp_line
			(start 0.120396 0.2794)
			(end -0.12065 0.2794)
			(stroke
				(width 0.1)
				(type default)
			)
			(layer "F.Fab")
		)
		(fp_line
			(start -0.12065 -0.2794)
			(end 0.12065 -0.2794)
			(stroke
				(width 0.1)
				(type default)
			)
			(layer "F.Fab")
		)
		(fp_line
			(start 0.12065 -0.2794)
			(end 0.12065 -0.3048)
			(stroke
				(width 0.1)
				(type default)
			)
			(layer "F.Fab")
		)
		(fp_line
			(start 0.12065 -0.3048)
			(end 0.67945 -0.3048)
			(stroke
				(width 0.1)
				(type default)
			)
			(layer "F.Fab")
		)
		(fp_line
			(start 0.67945 -0.3048)
			(end 0.67945 0.3048)
			(stroke
				(width 0.1)
				(type default)
			)
			(layer "F.Fab")
		)
		(fp_line
			(start -0.67945 -0.305054)
			(end -0.12065 -0.305054)
			(stroke
				(width 0.1)
				(type default)
			)
			(layer "F.Fab")
		)
		(fp_line
			(start -0.12065 -0.305054)
			(end -0.12065 -0.2794)
			(stroke
				(width 0.1)
				(type default)
			)
			(layer "F.Fab")
		)
		(pad "1" smd circle
			(at -0.40005 0 270)
			(size 0 0)
			(layers "F.Cu" "F.Mask" "F.Paste")
			(net "PVCCIN_CPU0")
		)
		(pad "2" smd circle
			(at 0.40005 0 270)
			(size 0 0)
			(layers "F.Cu" "F.Mask" "F.Paste")
			(net "GND")
		)
	)
	(footprint ""
		(layer "F.Cu")
		(at 226.503738 -220.815916 90)
		(property "Reference" "R996"
			(at 0 0 90)
			(layer "F.SilkS")
			(hide yes)
			(effects
				(font
					(size 1.27 1.27)
				)
			)
		)
		(property "Value" ""
			(at 0 0 90)
			(layer "F.Fab")
			(effects
				(font
					(size 1.27 1.27)
				)
			)
		)
		(duplicate_pad_numbers_are_jumpers no)
		(fp_line
			(start 0.7874 -0.4064)
			(end 0.7874 0.4064)
			(stroke
				(width 0.1524)
				(type default)
			)
			(layer "F.SilkS")
		)
		(fp_line
			(start -0.7874 -0.4064)
			(end 0.7874 -0.4064)
			(stroke
				(width 0.1524)
				(type default)
			)
			(layer "F.SilkS")
		)
		(fp_line
			(start 0.7874 0.4064)
			(end -0.7874 0.4064)
			(stroke
				(width 0.1524)
				(type default)
			)
			(layer "F.SilkS")
		)
		(fp_line
			(start -0.7874 0.4064)
			(end -0.7874 -0.4064)
			(stroke
				(width 0.1524)
				(type default)
			)
			(layer "F.SilkS")
		)
		(fp_line
			(start -0.12065 -0.305054)
			(end -0.12065 -0.2794)
			(stroke
				(width 0.1)
				(type default)
			)
			(layer "F.Fab")
		)
		(fp_line
			(start -0.67945 -0.305054)
			(end -0.12065 -0.305054)
			(stroke
				(width 0.1)
				(type default)
			)
			(layer "F.Fab")
		)
		(fp_line
			(start 0.67945 -0.3048)
			(end 0.67945 0.3048)
			(stroke
				(width 0.1)
				(type default)
			)
			(layer "F.Fab")
		)
		(fp_line
			(start 0.12065 -0.3048)
			(end 0.67945 -0.3048)
			(stroke
				(width 0.1)
				(type default)
			)
			(layer "F.Fab")
		)
		(fp_line
			(start 0.12065 -0.2794)
			(end 0.12065 -0.3048)
			(stroke
				(width 0.1)
				(type default)
			)
			(layer "F.Fab")
		)
		(fp_line
			(start -0.12065 -0.2794)
			(end 0.12065 -0.2794)
			(stroke
				(width 0.1)
				(type default)
			)
			(layer "F.Fab")
		)
		(fp_line
			(start 0.120396 0.2794)
			(end -0.12065 0.2794)
			(stroke
				(width 0.1)
				(type default)
			)
			(layer "F.Fab")
		)
		(fp_line
			(start -0.12065 0.2794)
			(end -0.12065 0.3048)
			(stroke
				(width 0.1)
				(type default)
			)
			(layer "F.Fab")
		)
		(fp_line
			(start 0.67945 0.3048)
			(end 0.120396 0.3048)
			(stroke
				(width 0.1)
				(type default)
			)
			(layer "F.Fab")
		)
		(fp_line
			(start 0.120396 0.3048)
			(end 0.120396 0.2794)
			(stroke
				(width 0.1)
				(type default)
			)
			(layer "F.Fab")
		)
		(fp_line
			(start -0.12065 0.3048)
			(end -0.67945 0.3048)
			(stroke
				(width 0.1)
				(type default)
			)
			(layer "F.Fab")
		)
		(fp_line
			(start -0.67945 0.3048)
			(end -0.67945 -0.305054)
			(stroke
				(width 0.1)
				(type default)
			)
			(layer "F.Fab")
		)
		(pad "1" smd circle
			(at -0.40005 0 90)
			(size 0 0)
			(layers "F.Cu" "F.Mask" "F.Paste")
			(net "SMB_S3M_CPU1_SDA")
		)
		(pad "2" smd circle
			(at 0.40005 0 90)
			(size 0 0)
			(layers "F.Cu" "F.Mask" "F.Paste")
			(net "SMB_S3M_CPU1_R_SDA")
		)
	)
)
